# T6G (Grand Teton) — schematic netlist excerpt (pin names and nets, part order shuffled) for the footprints in the layout excerpt that follows; sources: Cadence DE-HDL packaged netlist, KiCad conversion of 04192023_DAF0TMB3IC0_F0TG_MB_C_brd_V02_OCP.brd

PC547  Q_CAP  2.2UF 10V 10% X6S  pkg C0402  page 195 : A = PVDDCR_CPU0_P0_VCC4 ; B = GND
PR1134  Q_RES  120K 1% CHIP  pkg 0402LF  page 263 : A = AGND_HSC ; B = HSC_MODE_1

(kicad_pcb
	(version 20260206)
	(generator "pcbnew")
	(generator_version "10.0")
	(general
		(thickness 1.6)
		(legacy_teardrops no)
	)
	(paper "A4")
	(title_block
		(title "04192023_DAF0TMB3IC0_F0TG_MB_C_brd_V02_OCP.brd")
		(comment 1 "Grand Teton / footprints 3679-3680 of 8354")
	)
	(layers
		(0 "F.Cu" signal "TOP")
		(4 "In1.Cu" signal "GND")
		(6 "In2.Cu" signal "IN1")
		(8 "In3.Cu" signal "GND1")
		(10 "In4.Cu" signal "IN2")
		(12 "In5.Cu" signal "GND2")
		(14 "In6.Cu" signal "IN3")
		(16 "In7.Cu" signal "GND3")
		(18 "In8.Cu" signal "VCC")
		(20 "In9.Cu" signal "VCC1")
		(22 "In10.Cu" signal "GND4")
		(24 "In11.Cu" signal "IN4")
		(26 "In12.Cu" signal "GND5")
		(28 "In13.Cu" signal "IN5")
		(30 "In14.Cu" signal "GND6")
		(32 "In15.Cu" signal "IN6")
		(34 "In16.Cu" signal "GND7")
		(2 "B.Cu" signal "BOTTOM")
		(9 "F.Adhes" user "F.Adhesive")
		(11 "B.Adhes" user "B.Adhesive")
		(13 "F.Paste" user "Package Geometry/Pastemask Top")
		(15 "B.Paste" user "Package Geometry/Pastemask Bottom")
		(5 "F.SilkS" user "Ref Des/Silkscreen Top")
		(7 "B.SilkS" user "Ref Des/Silkscreen Bottom")
		(1 "F.Mask" user "Board Geometry/Soldermask Top")
		(3 "B.Mask" user "Board Geometry/Soldermask Bottom")
		(17 "Dwgs.User" user "User.Drawings")
		(19 "Cmts.User" user "User.Comments")
		(21 "Eco1.User" user "User.Eco1")
		(23 "Eco2.User" user "User.Eco2")
		(25 "Edge.Cuts" user "Board Geometry/Outline")
		(27 "Margin" user)
		(31 "F.CrtYd" user "Package Geometry/Place Bound Top")
		(29 "B.CrtYd" user "Package Geometry/Place Bound Bottom")
		(35 "F.Fab" user "Ref Des/Assembly Top")
		(33 "B.Fab" user "Ref Des/Assembly Bottom")
	)
	(footprint ""
		(layer "F.Cu")
		(at 204.7621 -407.068782 180)
		(property "Reference" "PR1134"
			(at 0 0 180)
			(layer "F.SilkS")
			(hide yes)
			(effects
				(font
					(size 1.27 1.27)
				)
			)
		)
		(property "Value" ""
			(at 0 0 180)
			(layer "F.Fab")
			(effects
				(font
					(size 1.27 1.27)
				)
			)
		)
		(duplicate_pad_numbers_are_jumpers no)
		(fp_line
			(start 0.7874 0.4064)
			(end -0.7874 0.4064)
			(stroke
				(width 0.1524)
				(type default)
			)
			(layer "F.SilkS")
		)
		(fp_line
			(start 0.7874 -0.4064)
			(end 0.7874 0.4064)
			(stroke
				(width 0.1524)
				(type default)
			)
			(layer "F.SilkS")
		)
		(fp_line
			(start -0.7874 0.4064)
			(end -0.7874 -0.4064)
			(stroke
				(width 0.1524)
				(type default)
			)
			(layer "F.SilkS")
		)
		(fp_line
			(start -0.7874 -0.4064)
			(end 0.7874 -0.4064)
			(stroke
				(width 0.1524)
				(type default)
			)
			(layer "F.SilkS")
		)
		(fp_line
			(start 0.67945 0.3048)
			(end 0.120396 0.3048)
			(stroke
				(width 0.1)
				(type default)
			)
			(layer "F.Fab")
		)
		(fp_line
			(start 0.67945 -0.3048)
			(end 0.67945 0.3048)
			(stroke
				(width 0.1)
				(type default)
			)
			(layer "F.Fab")
		)
		(fp_line
			(start 0.12065 -0.2794)
			(end 0.12065 -0.3048)
			(stroke
				(width 0.1)
				(type default)
			)
			(layer "F.Fab")
		)
		(fp_line
			(start 0.12065 -0.3048)
			(end 0.67945 -0.3048)
			(stroke
				(width 0.1)
				(type default)
			)
			(layer "F.Fab")
		)
		(fp_line
			(start 0.120396 0.3048)
			(end 0.120396 0.2794)
			(stroke
				(width 0.1)
				(type default)
			)
			(layer "F.Fab")
		)
		(fp_line
			(start 0.120396 0.2794)
			(end -0.12065 0.2794)
			(stroke
				(width 0.1)
				(type default)
			)
			(layer "F.Fab")
		)
		(fp_line
			(start -0.12065 0.3048)
			(end -0.67945 0.3048)
			(stroke
				(width 0.1)
				(type default)
			)
			(layer "F.Fab")
		)
		(fp_line
			(start -0.12065 0.2794)
			(end -0.12065 0.3048)
			(stroke
				(width 0.1)
				(type default)
			)
			(layer "F.Fab")
		)
		(fp_line
			(start -0.12065 -0.2794)
			(end 0.12065 -0.2794)
			(stroke
				(width 0.1)
				(type default)
			)
			(layer "F.Fab")
		)
		(fp_line
			(start -0.12065 -0.305054)
			(end -0.12065 -0.2794)
			(stroke
				(width 0.1)
				(type default)
			)
			(layer "F.Fab")
		)
		(fp_line
			(start -0.67945 0.3048)
			(end -0.67945 -0.305054)
			(stroke
				(width 0.1)
				(type default)
			)
			(layer "F.Fab")
		)
		(fp_line
			(start -0.67945 -0.305054)
			(end -0.12065 -0.305054)
			(stroke
				(width 0.1)
				(type default)
			)
			(layer "F.Fab")
		)
		(pad "1" smd circle
			(at -0.40005 0 180)
			(size 0 0)
			(layers "F.Cu" "F.Mask" "F.Paste")
			(net "AGND_HSC")
		)
		(pad "2" smd circle
			(at 0.40005 0 180)
			(size 0 0)
			(layers "F.Cu" "F.Mask" "F.Paste")
			(net "HSC_MODE_1")
		)
	)
	(footprint ""
		(layer "F.Cu")
		(at 393.092178 -180.078634 -90)
		(property "Reference" "PC547"
			(at 0 0 270)
			(layer "F.SilkS")
			(hide yes)
			(effects
				(font
					(size 1.27 1.27)
				)
			)
		)
		(property "Value" ""
			(at 0 0 270)
			(layer "F.Fab")
			(effects
				(font
					(size 1.27 1.27)
				)
			)
		)
		(duplicate_pad_numbers_are_jumpers no)
		(fp_line
			(start -0.7874 0.4064)
			(end -0.7874 -0.4064)
			(stroke
				(width 0.1524)
				(type default)
			)
			(layer "F.SilkS")
		)
		(fp_line
			(start -0.134366 0.4064)
			(end -0.7874 0.4064)
			(stroke
				(width 0.1524)
				(type default)
			)
			(layer "F.SilkS")
		)
		(fp_line
			(start 0.7874 0.4064)
			(end 0.449834 0.4064)
			(stroke
				(width 0.1524)
				(type default)
			)
			(layer "F.SilkS")
		)
		(fp_line
			(start -0.7874 -0.4064)
			(end 0.7874 -0.4064)
			(stroke
				(width 0.1524)
				(type default)
			)
			(layer "F.SilkS")
		)
		(fp_line
			(start 0.7874 -0.4064)
			(end 0.7874 0.4064)
			(stroke
				(width 0.1524)
				(type default)
			)
			(layer "F.SilkS")
		)
		(fp_line
			(start -0.67945 0.3048)
			(end -0.67945 -0.305054)
			(stroke
				(width 0.1)
				(type default)
			)
			(layer "F.Fab")
		)
		(fp_line
			(start -0.12065 0.3048)
			(end -0.67945 0.3048)
			(stroke
				(width 0.1)
				(type default)
			)
			(layer "F.Fab")
		)
		(fp_line
			(start 0.120396 0.3048)
			(end 0.120396 0.2794)
			(stroke
				(width 0.1)
				(type default)
			)
			(layer "F.Fab")
		)
		(fp_line
			(start 0.67945 0.3048)
			(end 0.120396 0.3048)
			(stroke
				(width 0.1)
				(type default)
			)
			(layer "F.Fab")
		)
		(fp_line
			(start -0.12065 0.2794)
			(end -0.12065 0.3048)
			(stroke
				(width 0.1)
				(type default)
			)
			(layer "F.Fab")
		)
		(fp_line
			(start 0.120396 0.2794)
			(end -0.12065 0.2794)
			(stroke
				(width 0.1)
				(type default)
			)
			(layer "F.Fab")
		)
		(fp_line
			(start -0.12065 -0.2794)
			(end 0.12065 -0.2794)
			(stroke
				(width 0.1)
				(type default)
			)
			(layer "F.Fab")
		)
		(fp_line
			(start 0.12065 -0.2794)
			(end 0.12065 -0.3048)
			(stroke
				(width 0.1)
				(type default)
			)
			(layer "F.Fab")
		)
		(fp_line
			(start 0.12065 -0.3048)
			(end 0.67945 -0.3048)
			(stroke
				(width 0.1)
				(type default)
			)
			(layer "F.Fab")
		)
		(fp_line
			(start 0.67945 -0.3048)
			(end 0.67945 0.3048)
			(stroke
				(width 0.1)
				(type default)
			)
			(layer "F.Fab")
		)
		(fp_line
			(start -0.67945 -0.305054)
			(end -0.12065 -0.305054)
			(stroke
				(width 0.1)
				(type default)
			)
			(layer "F.Fab")
		)
		(fp_line
			(start -0.12065 -0.305054)
			(end -0.12065 -0.2794)
			(stroke
				(width 0.1)
				(type default)
			)
			(layer "F.Fab")
		)
		(pad "1" smd circle
			(at -0.40005 0 270)
			(size 0 0)
			(layers "F.Cu" "F.Mask" "F.Paste")
			(net "PVDDCR_CPU0_P0_VCC4")
		)
		(pad "2" smd circle
			(at 0.40005 0 270)
			(size 0 0)
			(layers "F.Cu" "F.Mask" "F.Paste")
			(net "GND")
		)
	)
)
